(kicad_pcb
	(version 20260206)
	(generator "pcbnew")
	(generator_version "10.0")
	(general
		(thickness 1.6)
		(legacy_teardrops no)
	)
	(paper "A4")
	(title_block
		(title "03242023_DA0F0TMBIJ0_F0T_Motherboard_J_brd_V01_OCP.brd")
		(comment 1 "Grand Teton / footprints 5223-5228 of 6105")
	)
	(layers
		(0 "F.Cu" signal "TOP")
		(4 "In1.Cu" signal "GND")
		(6 "In2.Cu" signal "IN1")
		(8 "In3.Cu" signal "GND1")
		(10 "In4.Cu" signal "IN2")
		(12 "In5.Cu" signal "GND2")
		(14 "In6.Cu" signal "IN3")
		(16 "In7.Cu" signal "GND3")
		(18 "In8.Cu" signal "VCC")
		(20 "In9.Cu" signal "VCC1")
		(22 "In10.Cu" signal "GND4")
		(24 "In11.Cu" signal "IN4")
		(26 "In12.Cu" signal "GND5")
		(28 "In13.Cu" signal "IN5")
		(30 "In14.Cu" signal "GND6")
		(32 "In15.Cu" signal "IN6")
		(34 "In16.Cu" signal "GND7")
		(2 "B.Cu" signal "BOTTOM")
		(9 "F.Adhes" user "F.Adhesive")
		(11 "B.Adhes" user "B.Adhesive")
		(13 "F.Paste" user "Package Geometry/Pastemask Top")
		(15 "B.Paste" user "Package Geometry/Pastemask Bottom")
		(5 "F.SilkS" user "Ref Des/Silkscreen Top")
		(7 "B.SilkS" user "Ref Des/Silkscreen Bottom")
		(1 "F.Mask" user "Board Geometry/Soldermask Top")
		(3 "B.Mask" user "Board Geometry/Soldermask Bottom")
		(17 "Dwgs.User" user "User.Drawings")
		(19 "Cmts.User" user "User.Comments")
		(21 "Eco1.User" user "User.Eco1")
		(23 "Eco2.User" user "User.Eco2")
		(25 "Edge.Cuts" user "Board Geometry/Outline")
		(27 "Margin" user)
		(31 "F.CrtYd" user "Package Geometry/Place Bound Top")
		(29 "B.CrtYd" user "Package Geometry/Place Bound Bottom")
		(35 "F.Fab" user "Ref Des/Assembly Top")
		(33 "B.Fab" user "Ref Des/Assembly Bottom")
	)
	(footprint ""
		(layer "B.Cu")
		(at 420.682166 -136.162034 180)
		(property "Reference" "PR107"
			(at 0 0 0)
			(layer "B.SilkS")
			(hide yes)
			(effects
				(font
					(size 1.27 1.27)
				)
				(justify mirror)
			)
		)
		(property "Value" ""
			(at 0 0 0)
			(layer "B.Fab")
			(effects
				(font
					(size 1.27 1.27)
				)
				(justify mirror)
			)
		)
		(duplicate_pad_numbers_are_jumpers no)
		(fp_line
			(start 0.7874 0.4064)
			(end 0.7874 -0.4064)
			(stroke
				(width 0.1524)
				(type default)
			)
			(layer "B.SilkS")
		)
		(fp_line
			(start 0.7874 -0.4064)
			(end -0.7874 -0.4064)
			(stroke
				(width 0.1524)
				(type default)
			)
			(layer "B.SilkS")
		)
		(fp_line
			(start -0.7874 0.4064)
			(end 0.7874 0.4064)
			(stroke
				(width 0.1524)
				(type default)
			)
			(layer "B.SilkS")
		)
		(fp_line
			(start -0.7874 -0.4064)
			(end -0.7874 0.4064)
			(stroke
				(width 0.1524)
				(type default)
			)
			(layer "B.SilkS")
		)
		(fp_line
			(start 0.67945 0.3048)
			(end 0.67945 -0.305054)
			(stroke
				(width 0.1)
				(type default)
			)
			(layer "B.Fab")
		)
		(fp_line
			(start 0.67945 -0.305054)
			(end 0.12065 -0.305054)
			(stroke
				(width 0.1)
				(type default)
			)
			(layer "B.Fab")
		)
		(fp_line
			(start 0.12065 0.3048)
			(end 0.67945 0.3048)
			(stroke
				(width 0.1)
				(type default)
			)
			(layer "B.Fab")
		)
		(fp_line
			(start 0.12065 0.2794)
			(end 0.12065 0.3048)
			(stroke
				(width 0.1)
				(type default)
			)
			(layer "B.Fab")
		)
		(fp_line
			(start 0.12065 -0.2794)
			(end -0.12065 -0.2794)
			(stroke
				(width 0.1)
				(type default)
			)
			(layer "B.Fab")
		)
		(fp_line
			(start 0.12065 -0.305054)
			(end 0.12065 -0.2794)
			(stroke
				(width 0.1)
				(type default)
			)
			(layer "B.Fab")
		)
		(fp_line
			(start -0.120396 0.3048)
			(end -0.120396 0.2794)
			(stroke
				(width 0.1)
				(type default)
			)
			(layer "B.Fab")
		)
		(fp_line
			(start -0.120396 0.2794)
			(end 0.12065 0.2794)
			(stroke
				(width 0.1)
				(type default)
			)
			(layer "B.Fab")
		)
		(fp_line
			(start -0.12065 -0.2794)
			(end -0.12065 -0.3048)
			(stroke
				(width 0.1)
				(type default)
			)
			(layer "B.Fab")
		)
		(fp_line
			(start -0.12065 -0.3048)
			(end -0.67945 -0.3048)
			(stroke
				(width 0.1)
				(type default)
			)
			(layer "B.Fab")
		)
		(fp_line
			(start -0.67945 0.3048)
			(end -0.120396 0.3048)
			(stroke
				(width 0.1)
				(type default)
			)
			(layer "B.Fab")
		)
		(fp_line
			(start -0.67945 -0.3048)
			(end -0.67945 0.3048)
			(stroke
				(width 0.1)
				(type default)
			)
			(layer "B.Fab")
		)
		(pad "1" smd circle
			(at 0.40005 0)
			(size 0 0)
			(layers "B.Cu" "B.Mask" "B.Paste")
			(net "P12V_AUX")
		)
		(pad "2" smd circle
			(at -0.40005 0)
			(size 0 0)
			(layers "B.Cu" "B.Mask" "B.Paste")
			(net "PVCCINFAON_CPU0_CSPIN")
		)
	)
	(footprint ""
		(layer "B.Cu")
		(at 114.693446 -358.566212 180)
		(property "Reference" "PR637"
			(at 0 0 0)
			(layer "B.SilkS")
			(hide yes)
			(effects
				(font
					(size 1.27 1.27)
				)
				(justify mirror)
			)
		)
		(property "Value" ""
			(at 0 0 0)
			(layer "B.Fab")
			(effects
				(font
					(size 1.27 1.27)
				)
				(justify mirror)
			)
		)
		(duplicate_pad_numbers_are_jumpers no)
		(fp_line
			(start 0.7874 0.4064)
			(end 0.7874 -0.4064)
			(stroke
				(width 0.1524)
				(type default)
			)
			(layer "B.SilkS")
		)
		(fp_line
			(start 0.7874 -0.4064)
			(end -0.7874 -0.4064)
			(stroke
				(width 0.1524)
				(type default)
			)
			(layer "B.SilkS")
		)
		(fp_line
			(start -0.7874 0.4064)
			(end 0.7874 0.4064)
			(stroke
				(width 0.1524)
				(type default)
			)
			(layer "B.SilkS")
		)
		(fp_line
			(start -0.7874 -0.4064)
			(end -0.7874 0.4064)
			(stroke
				(width 0.1524)
				(type default)
			)
			(layer "B.SilkS")
		)
		(fp_line
			(start 0.67945 0.3048)
			(end 0.67945 -0.305054)
			(stroke
				(width 0.1)
				(type default)
			)
			(layer "B.Fab")
		)
		(fp_line
			(start 0.67945 -0.305054)
			(end 0.12065 -0.305054)
			(stroke
				(width 0.1)
				(type default)
			)
			(layer "B.Fab")
		)
		(fp_line
			(start 0.12065 0.3048)
			(end 0.67945 0.3048)
			(stroke
				(width 0.1)
				(type default)
			)
			(layer "B.Fab")
		)
		(fp_line
			(start 0.12065 0.2794)
			(end 0.12065 0.3048)
			(stroke
				(width 0.1)
				(type default)
			)
			(layer "B.Fab")
		)
		(fp_line
			(start 0.12065 -0.2794)
			(end -0.12065 -0.2794)
			(stroke
				(width 0.1)
				(type default)
			)
			(layer "B.Fab")
		)
		(fp_line
			(start 0.12065 -0.305054)
			(end 0.12065 -0.2794)
			(stroke
				(width 0.1)
				(type default)
			)
			(layer "B.Fab")
		)
		(fp_line
			(start -0.120396 0.3048)
			(end -0.120396 0.2794)
			(stroke
				(width 0.1)
				(type default)
			)
			(layer "B.Fab")
		)
		(fp_line
			(start -0.120396 0.2794)
			(end 0.12065 0.2794)
			(stroke
				(width 0.1)
				(type default)
			)
			(layer "B.Fab")
		)
		(fp_line
			(start -0.12065 -0.2794)
			(end -0.12065 -0.3048)
			(stroke
				(width 0.1)
				(type default)
			)
			(layer "B.Fab")
		)
		(fp_line
			(start -0.12065 -0.3048)
			(end -0.67945 -0.3048)
			(stroke
				(width 0.1)
				(type default)
			)
			(layer "B.Fab")
		)
		(fp_line
			(start -0.67945 0.3048)
			(end -0.120396 0.3048)
			(stroke
				(width 0.1)
				(type default)
			)
			(layer "B.Fab")
		)
		(fp_line
			(start -0.67945 -0.3048)
			(end -0.67945 0.3048)
			(stroke
				(width 0.1)
				(type default)
			)
			(layer "B.Fab")
		)
		(pad "1" smd circle
			(at 0.40005 0)
			(size 0 0)
			(layers "B.Cu" "B.Mask" "B.Paste")
			(net "PVCCIN_CPU1_ATSEN")
		)
		(pad "2" smd circle
			(at -0.40005 0)
			(size 0 0)
			(layers "B.Cu" "B.Mask" "B.Paste")
			(net "GND")
		)
	)
	(footprint ""
		(layer "B.Cu")
		(at 126.065026 -339.602572 -90)
		(property "Reference" "PR296"
			(at 0 0 90)
			(layer "B.SilkS")
			(hide yes)
			(effects
				(font
					(size 1.27 1.27)
				)
				(justify mirror)
			)
		)
		(property "Value" ""
			(at 0 0 90)
			(layer "B.Fab")
			(effects
				(font
					(size 1.27 1.27)
				)
				(justify mirror)
			)
		)
		(duplicate_pad_numbers_are_jumpers no)
		(fp_line
			(start -0.7874 0.4064)
			(end 0.7874 0.4064)
			(stroke
				(width 0.1524)
				(type default)
			)
			(layer "B.SilkS")
		)
		(fp_line
			(start 0.7874 0.4064)
			(end 0.7874 -0.4064)
			(stroke
				(width 0.1524)
				(type default)
			)
			(layer "B.SilkS")
		)
		(fp_line
			(start -0.7874 -0.4064)
			(end -0.7874 0.4064)
			(stroke
				(width 0.1524)
				(type default)
			)
			(layer "B.SilkS")
		)
		(fp_line
			(start 0.7874 -0.4064)
			(end -0.7874 -0.4064)
			(stroke
				(width 0.1524)
				(type default)
			)
			(layer "B.SilkS")
		)
		(fp_line
			(start -0.67945 0.3048)
			(end -0.120396 0.3048)
			(stroke
				(width 0.1)
				(type default)
			)
			(layer "B.Fab")
		)
		(fp_line
			(start -0.120396 0.3048)
			(end -0.120396 0.2794)
			(stroke
				(width 0.1)
				(type default)
			)
			(layer "B.Fab")
		)
		(fp_line
			(start 0.12065 0.3048)
			(end 0.67945 0.3048)
			(stroke
				(width 0.1)
				(type default)
			)
			(layer "B.Fab")
		)
		(fp_line
			(start 0.67945 0.3048)
			(end 0.67945 -0.305054)
			(stroke
				(width 0.1)
				(type default)
			)
			(layer "B.Fab")
		)
		(fp_line
			(start -0.120396 0.2794)
			(end 0.12065 0.2794)
			(stroke
				(width 0.1)
				(type default)
			)
			(layer "B.Fab")
		)
		(fp_line
			(start 0.12065 0.2794)
			(end 0.12065 0.3048)
			(stroke
				(width 0.1)
				(type default)
			)
			(layer "B.Fab")
		)
		(fp_line
			(start -0.12065 -0.2794)
			(end -0.12065 -0.3048)
			(stroke
				(width 0.1)
				(type default)
			)
			(layer "B.Fab")
		)
		(fp_line
			(start 0.12065 -0.2794)
			(end -0.12065 -0.2794)
			(stroke
				(width 0.1)
				(type default)
			)
			(layer "B.Fab")
		)
		(fp_line
			(start -0.67945 -0.3048)
			(end -0.67945 0.3048)
			(stroke
				(width 0.1)
				(type default)
			)
			(layer "B.Fab")
		)
		(fp_line
			(start -0.12065 -0.3048)
			(end -0.67945 -0.3048)
			(stroke
				(width 0.1)
				(type default)
			)
			(layer "B.Fab")
		)
		(fp_line
			(start 0.12065 -0.305054)
			(end 0.12065 -0.2794)
			(stroke
				(width 0.1)
				(type default)
			)
			(layer "B.Fab")
		)
		(fp_line
			(start 0.67945 -0.305054)
			(end 0.12065 -0.305054)
			(stroke
				(width 0.1)
				(type default)
			)
			(layer "B.Fab")
		)
		(pad "1" smd circle
			(at 0.40005 0 90)
			(size 0 0)
			(layers "B.Cu" "B.Mask" "B.Paste")
			(net "PVCCIN_CPU1_VOS5")
		)
		(pad "2" smd circle
			(at -0.40005 0 90)
			(size 0 0)
			(layers "B.Cu" "B.Mask" "B.Paste")
			(net "PVCCIN_CPU1")
		)
	)
	(footprint ""
		(layer "B.Cu")
		(at 366.120934 -252.176026 -90)
		(property "Reference" "C367"
			(at 0 0 90)
			(layer "B.SilkS")
			(hide yes)
			(effects
				(font
					(size 1.27 1.27)
				)
				(justify mirror)
			)
		)
		(property "Value" ""
			(at 0 0 90)
			(layer "B.Fab")
			(effects
				(font
					(size 1.27 1.27)
				)
				(justify mirror)
			)
		)
		(duplicate_pad_numbers_are_jumpers no)
		(fp_line
			(start -1.524 0.762)
			(end 1.524 0.762)
			(stroke
				(width 0.1524)
				(type default)
			)
			(layer "B.SilkS")
		)
		(fp_line
			(start 1.524 0.762)
			(end 1.524 -0.762)
			(stroke
				(width 0.1524)
				(type default)
			)
			(layer "B.SilkS")
		)
		(fp_line
			(start -1.524 -0.762)
			(end -1.524 0.762)
			(stroke
				(width 0.1524)
				(type default)
			)
			(layer "B.SilkS")
		)
		(fp_line
			(start 1.524 -0.762)
			(end -1.524 -0.762)
			(stroke
				(width 0.1524)
				(type default)
			)
			(layer "B.SilkS")
		)
		(fp_line
			(start -1.1049 0.724916)
			(end -1.1049 -0.724916)
			(stroke
				(width 0.1)
				(type default)
			)
			(layer "B.Fab")
		)
		(fp_line
			(start 1.1049 0.724916)
			(end -1.1049 0.724916)
			(stroke
				(width 0.1)
				(type default)
			)
			(layer "B.Fab")
		)
		(fp_line
			(start -1.1049 -0.724916)
			(end 1.1049 -0.724916)
			(stroke
				(width 0.1)
				(type default)
			)
			(layer "B.Fab")
		)
		(fp_line
			(start 1.1049 -0.724916)
			(end 1.1049 0.724916)
			(stroke
				(width 0.1)
				(type default)
			)
			(layer "B.Fab")
		)
		(pad "1" smd rect
			(at 0.889 0 270)
			(size 1.016 1.27)
			(layers "B.Cu" "B.Mask" "B.Paste")
			(net "PVCCIN_CPU0")
		)
		(pad "2" smd rect
			(at -0.889 0 270)
			(size 1.016 1.27)
			(layers "B.Cu" "B.Mask" "B.Paste")
			(net "GND")
		)
	)
	(footprint ""
		(layer "B.Cu")
		(at 197.41388 -107.495848)
		(property "Reference" "R4056"
			(at 0 0 0)
			(layer "B.SilkS")
			(hide yes)
			(effects
				(font
					(size 1.27 1.27)
				)
				(justify mirror)
			)
		)
		(property "Value" ""
			(at 0 0 0)
			(layer "B.Fab")
			(effects
				(font
					(size 1.27 1.27)
				)
				(justify mirror)
			)
		)
		(duplicate_pad_numbers_are_jumpers no)
		(fp_line
			(start -0.7874 -0.4064)
			(end -0.7874 0.4064)
			(stroke
				(width 0.1524)
				(type default)
			)
			(layer "B.SilkS")
		)
		(fp_line
			(start -0.7874 0.4064)
			(end 0.7874 0.4064)
			(stroke
				(width 0.1524)
				(type default)
			)
			(layer "B.SilkS")
		)
		(fp_line
			(start 0.7874 -0.4064)
			(end -0.7874 -0.4064)
			(stroke
				(width 0.1524)
				(type default)
			)
			(layer "B.SilkS")
		)
		(fp_line
			(start 0.7874 0.4064)
			(end 0.7874 -0.4064)
			(stroke
				(width 0.1524)
				(type default)
			)
			(layer "B.SilkS")
		)
		(fp_line
			(start -0.67945 -0.3048)
			(end -0.67945 0.3048)
			(stroke
				(width 0.1)
				(type default)
			)
			(layer "B.Fab")
		)
		(fp_line
			(start -0.67945 0.3048)
			(end -0.120396 0.3048)
			(stroke
				(width 0.1)
				(type default)
			)
			(layer "B.Fab")
		)
		(fp_line
			(start -0.12065 -0.3048)
			(end -0.67945 -0.3048)
			(stroke
				(width 0.1)
				(type default)
			)
			(layer "B.Fab")
		)
		(fp_line
			(start -0.12065 -0.2794)
			(end -0.12065 -0.3048)
			(stroke
				(width 0.1)
				(type default)
			)
			(layer "B.Fab")
		)
		(fp_line
			(start -0.120396 0.2794)
			(end 0.12065 0.2794)
			(stroke
				(width 0.1)
				(type default)
			)
			(layer "B.Fab")
		)
		(fp_line
			(start -0.120396 0.3048)
			(end -0.120396 0.2794)
			(stroke
				(width 0.1)
				(type default)
			)
			(layer "B.Fab")
		)
		(fp_line
			(start 0.12065 -0.305054)
			(end 0.12065 -0.2794)
			(stroke
				(width 0.1)
				(type default)
			)
			(layer "B.Fab")
		)
		(fp_line
			(start 0.12065 -0.2794)
			(end -0.12065 -0.2794)
			(stroke
				(width 0.1)
				(type default)
			)
			(layer "B.Fab")
		)
		(fp_line
			(start 0.12065 0.2794)
			(end 0.12065 0.3048)
			(stroke
				(width 0.1)
				(type default)
			)
			(layer "B.Fab")
		)
		(fp_line
			(start 0.12065 0.3048)
			(end 0.67945 0.3048)
			(stroke
				(width 0.1)
				(type default)
			)
			(layer "B.Fab")
		)
		(fp_line
			(start 0.67945 -0.305054)
			(end 0.12065 -0.305054)
			(stroke
				(width 0.1)
				(type default)
			)
			(layer "B.Fab")
		)
		(fp_line
			(start 0.67945 0.3048)
			(end 0.67945 -0.305054)
			(stroke
				(width 0.1)
				(type default)
			)
			(layer "B.Fab")
		)
		(pad "1" smd circle
			(at 0.40005 0 180)
			(size 0 0)
			(layers "B.Cu" "B.Mask" "B.Paste")
			(net "HSC_D_OC")
		)
		(pad "2" smd circle
			(at -0.40005 0 180)
			(size 0 0)
			(layers "B.Cu" "B.Mask" "B.Paste")
			(net "HSC_D_OC_R1")
		)
	)
	(footprint ""
		(layer "B.Cu")
		(at 229.87254 -125.040898 -90)
		(property "Reference" "C204"
			(at 0 0 90)
			(layer "B.SilkS")
			(hide yes)
			(effects
				(font
					(size 1.27 1.27)
				)
				(justify mirror)
			)
		)
		(property "Value" ""
			(at 0 0 90)
			(layer "B.Fab")
			(effects
				(font
					(size 1.27 1.27)
				)
				(justify mirror)
			)
		)
		(duplicate_pad_numbers_are_jumpers no)
		(fp_line
			(start -0.7874 0.4064)
			(end 0.7874 0.4064)
			(stroke
				(width 0.1524)
				(type default)
			)
			(layer "B.SilkS")
		)
		(fp_line
			(start 0.7874 0.4064)
			(end 0.7874 -0.4064)
			(stroke
				(width 0.1524)
				(type default)
			)
			(layer "B.SilkS")
		)
		(fp_line
			(start -0.7874 -0.4064)
			(end -0.7874 0.4064)
			(stroke
				(width 0.1524)
				(type default)
			)
			(layer "B.SilkS")
		)
		(fp_line
			(start 0.7874 -0.4064)
			(end -0.7874 -0.4064)
			(stroke
				(width 0.1524)
				(type default)
			)
			(layer "B.SilkS")
		)
		(fp_line
			(start -0.67945 0.3048)
			(end -0.120396 0.3048)
			(stroke
				(width 0.1)
				(type default)
			)
			(layer "B.Fab")
		)
		(fp_line
			(start -0.120396 0.3048)
			(end -0.120396 0.2794)
			(stroke
				(width 0.1)
				(type default)
			)
			(layer "B.Fab")
		)
		(fp_line
			(start 0.12065 0.3048)
			(end 0.67945 0.3048)
			(stroke
				(width 0.1)
				(type default)
			)
			(layer "B.Fab")
		)
		(fp_line
			(start 0.67945 0.3048)
			(end 0.67945 -0.305054)
			(stroke
				(width 0.1)
				(type default)
			)
			(layer "B.Fab")
		)
		(fp_line
			(start -0.120396 0.2794)
			(end 0.12065 0.2794)
			(stroke
				(width 0.1)
				(type default)
			)
			(layer "B.Fab")
		)
		(fp_line
			(start 0.12065 0.2794)
			(end 0.12065 0.3048)
			(stroke
				(width 0.1)
				(type default)
			)
			(layer "B.Fab")
		)
		(fp_line
			(start -0.12065 -0.2794)
			(end -0.12065 -0.3048)
			(stroke
				(width 0.1)
				(type default)
			)
			(layer "B.Fab")
		)
		(fp_line
			(start 0.12065 -0.2794)
			(end -0.12065 -0.2794)
			(stroke
				(width 0.1)
				(type default)
			)
			(layer "B.Fab")
		)
		(fp_line
			(start -0.67945 -0.3048)
			(end -0.67945 0.3048)
			(stroke
				(width 0.1)
				(type default)
			)
			(layer "B.Fab")
		)
		(fp_line
			(start -0.12065 -0.3048)
			(end -0.67945 -0.3048)
			(stroke
				(width 0.1)
				(type default)
			)
			(layer "B.Fab")
		)
		(fp_line
			(start 0.12065 -0.305054)
			(end 0.12065 -0.2794)
			(stroke
				(width 0.1)
				(type default)
			)
			(layer "B.Fab")
		)
		(fp_line
			(start 0.67945 -0.305054)
			(end 0.12065 -0.305054)
			(stroke
				(width 0.1)
				(type default)
			)
			(layer "B.Fab")
		)
		(pad "1" smd circle
			(at 0.40005 0 90)
			(size 0 0)
			(layers "B.Cu" "B.Mask" "B.Paste")
			(net "P3V3_DB2000_VDD")
		)
		(pad "2" smd circle
			(at -0.40005 0 90)
			(size 0 0)
			(layers "B.Cu" "B.Mask" "B.Paste")
			(net "GND")
		)
	)
)
